# BASEBOARD_FAB2 (Tioga Pass) — schematic netlist excerpt (pin names and nets, part order shuffled) for the footprints in the layout excerpt that follows; sources: Cadence DE-HDL packaged netlist, KiCad conversion of Wiwynn_Tioga_Pass_MB.brd

R6L8  RES  0.0 5% CHIP  pkg 0402  page 230 : A = P3V3 ; B = VR_PVTT_KLM_BIAS
U25W14  TTL1G07_A  74LVC1G07 IC  pkg SOP  page 255 : A = XDP_PRESENT_N ; Y = CPU_XDP_PRESENT_N
R6W37  RES  10.0 1% CHIP  pkg 0402  page 176 : A = SPA_MID_DBG2_TX_R ; B = SPA_MID_DBG2_TX

(kicad_pcb
	(version 20260206)
	(generator "pcbnew")
	(generator_version "10.0")
	(general
		(thickness 1.6)
		(legacy_teardrops no)
	)
	(paper "A4")
	(title_block
		(title "Wiwynn_Tioga_Pass_MB.brd")
		(comment 1 "Tioga Pass / footprints 2582-2584 of 4770")
	)
	(layers
		(0 "F.Cu" signal "TOP")
		(4 "In1.Cu" signal "L2GND")
		(6 "In2.Cu" signal "L3")
		(8 "In3.Cu" signal "L4GND")
		(10 "In4.Cu" signal "L5")
		(12 "In5.Cu" signal "L6GND")
		(14 "In6.Cu" signal "L7VCC")
		(16 "In7.Cu" signal "L8VCC")
		(18 "In8.Cu" signal "L9GND")
		(20 "In9.Cu" signal "L10")
		(22 "In10.Cu" signal "L11GND")
		(24 "In11.Cu" signal "L12")
		(26 "In12.Cu" signal "L13GND")
		(2 "B.Cu" signal "BOTTOM")
		(9 "F.Adhes" user "F.Adhesive")
		(11 "B.Adhes" user "B.Adhesive")
		(13 "F.Paste" user "Package Geometry/Pastemask Top")
		(15 "B.Paste" user "Package Geometry/Pastemask Bottom")
		(5 "F.SilkS" user "Ref Des/Silkscreen Top")
		(7 "B.SilkS" user "Ref Des/Silkscreen Bottom")
		(1 "F.Mask" user "Board Geometry/Soldermask Top")
		(3 "B.Mask" user "Board Geometry/Soldermask Bottom")
		(17 "Dwgs.User" user "User.Drawings")
		(19 "Cmts.User" user "User.Comments")
		(21 "Eco1.User" user "User.Eco1")
		(23 "Eco2.User" user "User.Eco2")
		(25 "Edge.Cuts" user "Board Geometry/Outline")
		(27 "Margin" user)
		(31 "F.CrtYd" user "Package Geometry/Place Bound Top")
		(29 "B.CrtYd" user "Package Geometry/Place Bound Bottom")
		(35 "F.Fab" user "Ref Des/Assembly Top")
		(33 "B.Fab" user "Ref Des/Assembly Bottom")
	)
	(footprint ""
		(layer "B.Cu")
		(at 445.503046 -150.810722 90)
		(property "Reference" "U25W14"
			(at 0.14986 2.621788 90)
			(unlocked yes)
			(layer "B.SilkS")
			(effects
				(font
					(size 1.27 0.964946)
					(thickness 0.000001)
				)
				(justify left mirror)
			)
		)
		(property "Value" ""
			(at 0 0 90)
			(layer "B.Fab")
			(effects
				(font
					(size 1.27 1.27)
				)
				(justify mirror)
			)
		)
		(duplicate_pad_numbers_are_jumpers no)
		(fp_circle
			(center 0.4699 -0.8382)
			(end 0.4699 -0.7112)
			(stroke
				(width 0.254)
				(type default)
			)
			(fill no)
			(layer "B.SilkS")
		)
		(fp_poly
			(pts
				(xy -0.21463 -0.450088) (xy -1.56337 -0.450088) (xy -1.56337 1.75006) (xy -0.21463 1.75006)
			)
			(stroke
				(width 0)
				(type default)
			)
			(fill no)
			(layer "B.CrtYd")
		)
		(fp_line
			(start -0.21463 -0.450088)
			(end -1.56337 -0.450088)
			(stroke
				(width 0.1)
				(type default)
			)
			(layer "B.Fab")
		)
		(fp_line
			(start -1.56337 -0.450088)
			(end -1.56337 1.75006)
			(stroke
				(width 0.1)
				(type default)
			)
			(layer "B.Fab")
		)
		(fp_line
			(start -0.21463 1.75006)
			(end -0.21463 -0.450088)
			(stroke
				(width 0.1)
				(type default)
			)
			(layer "B.Fab")
		)
		(fp_line
			(start -1.56337 1.75006)
			(end -0.21463 1.75006)
			(stroke
				(width 0.1)
				(type default)
			)
			(layer "B.Fab")
		)
		(fp_circle
			(center 0.4699 -0.8382)
			(end 0.4699 -0.7112)
			(stroke
				(width 0.254)
				(type default)
			)
			(fill no)
			(layer "B.Fab")
		)
		(pad "1" smd rect
			(at 0 0 270)
			(size 1.016 0.381)
			(layers "B.Cu" "B.Mask" "B.Paste")
			(net "Net_6509")
		)
		(pad "2" smd rect
			(at 0 0.649986 270)
			(size 1.016 0.381)
			(layers "B.Cu" "B.Mask" "B.Paste")
			(net "XDP_PRESENT_N")
		)
		(pad "3" smd rect
			(at 0 1.299972 270)
			(size 1.016 0.381)
			(layers "B.Cu" "B.Mask" "B.Paste")
			(net "GND")
		)
		(pad "4" smd rect
			(at -1.778 1.299972 270)
			(size 1.016 0.381)
			(layers "B.Cu" "B.Mask" "B.Paste")
			(net "CPU_XDP_PRESENT_N")
		)
		(pad "5" smd rect
			(at -1.778 0 270)
			(size 1.016 0.381)
			(layers "B.Cu" "B.Mask" "B.Paste")
			(net "P3V3_STBY")
		)
	)
	(footprint ""
		(layer "B.Cu")
		(at 174.5234 -146.939 -90)
		(property "Reference" "R6L8"
			(at 0 0 90)
			(layer "B.SilkS")
			(hide yes)
			(effects
				(font
					(size 1.27 1.27)
				)
				(justify mirror)
			)
		)
		(property "Value" ""
			(at 0 0 90)
			(layer "B.Fab")
			(effects
				(font
					(size 1.27 1.27)
				)
				(justify mirror)
			)
		)
		(duplicate_pad_numbers_are_jumpers no)
		(fp_rect
			(start -0.2794 -0.1016)
			(end 0.2794 0.9906)
			(stroke
				(width 0)
				(type default)
			)
			(fill no)
			(layer "B.CrtYd")
		)
		(fp_line
			(start -0.2794 0.9906)
			(end -0.2794 -0.1016)
			(stroke
				(width 0.1)
				(type default)
			)
			(layer "B.Fab")
		)
		(fp_line
			(start 0.2794 0.9906)
			(end -0.2794 0.9906)
			(stroke
				(width 0.1)
				(type default)
			)
			(layer "B.Fab")
		)
		(fp_line
			(start -0.2794 -0.1016)
			(end 0.2794 -0.1016)
			(stroke
				(width 0.1)
				(type default)
			)
			(layer "B.Fab")
		)
		(fp_line
			(start 0.2794 -0.1016)
			(end 0.2794 0.9906)
			(stroke
				(width 0.1)
				(type default)
			)
			(layer "B.Fab")
		)
		(pad "1" smd rect
			(at 0 0 90)
			(size 0.508 0.508)
			(layers "B.Cu" "B.Mask" "B.Paste")
			(net "P3V3")
		)
		(pad "2" smd rect
			(at 0 0.889 90)
			(size 0.508 0.508)
			(layers "B.Cu" "B.Mask" "B.Paste")
			(net "VR_PVTT_KLM_BIAS")
		)
		(zone
			(layer "B.Cu")
			(hatch none 0.5)
			(connect_pads
				(clearance 0)
			)
			(min_thickness 0.25)
			(keepout
				(tracks allowed)
				(vias not_allowed)
				(pads allowed)
				(copperpour not_allowed)
				(footprints allowed)
			)
			(placement
				(enabled no)
				(sheetname "")
			)
			(fill
				(thermal_gap 0.5)
				(thermal_bridge_width 0.5)
				(island_removal_mode 0)
			)
			(polygon
				(pts
					(xy 174.2694 -147.193) (xy 173.8884 -147.193) (xy 173.8884 -146.685) (xy 174.2694 -146.685)
				)
			)
		)
		(zone
			(layer "B.Cu")
			(hatch none 0.5)
			(connect_pads
				(clearance 0)
			)
			(min_thickness 0.25)
			(keepout
				(tracks not_allowed)
				(vias allowed)
				(pads allowed)
				(copperpour not_allowed)
				(footprints allowed)
			)
			(placement
				(enabled no)
				(sheetname "")
			)
			(fill
				(thermal_gap 0.5)
				(thermal_bridge_width 0.5)
				(island_removal_mode 0)
			)
			(polygon
				(pts
					(xy 174.2694 -147.193) (xy 173.8884 -147.193) (xy 173.8884 -146.685) (xy 174.2694 -146.685)
				)
			)
		)
	)
	(footprint ""
		(layer "B.Cu")
		(at 500.38 -151.0538 180)
		(property "Reference" "R6W37"
			(at 0.8382 -0.67818 180)
			(unlocked yes)
			(layer "B.SilkS")
			(effects
				(font
					(size 0.4064 0.254)
					(thickness 0.1524)
				)
				(justify left mirror)
			)
		)
		(property "Value" ""
			(at 0 0 0)
			(layer "B.Fab")
			(effects
				(font
					(size 1.27 1.27)
				)
				(justify mirror)
			)
		)
		(duplicate_pad_numbers_are_jumpers no)
		(fp_poly
			(pts
				(xy 0.2794 -0.1016) (xy -0.2794 -0.1016) (xy -0.2794 0.9906) (xy 0.2794 0.9906)
			)
			(stroke
				(width 0)
				(type default)
			)
			(fill no)
			(layer "B.CrtYd")
		)
		(fp_line
			(start 0.2794 0.9906)
			(end -0.2794 0.9906)
			(stroke
				(width 0.1)
				(type default)
			)
			(layer "B.Fab")
		)
		(fp_line
			(start 0.2794 -0.1016)
			(end 0.2794 0.9906)
			(stroke
				(width 0.1)
				(type default)
			)
			(layer "B.Fab")
		)
		(fp_line
			(start -0.2794 0.9906)
			(end -0.2794 -0.1016)
			(stroke
				(width 0.1)
				(type default)
			)
			(layer "B.Fab")
		)
		(fp_line
			(start -0.2794 -0.1016)
			(end 0.2794 -0.1016)
			(stroke
				(width 0.1)
				(type default)
			)
			(layer "B.Fab")
		)
		(pad "1" smd rect
			(at 0 0)
			(size 0.508 0.508)
			(layers "B.Cu" "B.Mask" "B.Paste")
			(net "SPA_MID_DBG2_TX_R")
		)
		(pad "2" smd rect
			(at 0 0.889)
			(size 0.508 0.508)
			(layers "B.Cu" "B.Mask" "B.Paste")
			(net "SPA_MID_DBG2_TX")
		)
		(zone
			(layer "B.Cu")
			(hatch none 0.5)
			(connect_pads
				(clearance 0)
			)
			(min_thickness 0.25)
			(keepout
				(tracks not_allowed)
				(vias allowed)
				(pads allowed)
				(copperpour not_allowed)
				(footprints allowed)
			)
			(placement
				(enabled no)
				(sheetname "")
			)
			(fill
				(thermal_gap 0.5)
				(thermal_bridge_width 0.5)
				(island_removal_mode 0)
			)
			(polygon
				(pts
					(xy 500.126 -151.6888) (xy 500.634 -151.6888) (xy 500.634 -151.3078) (xy 500.126 -151.3078)
				)
			)
		)
		(zone
			(layer "B.Cu")
			(hatch none 0.5)
			(connect_pads
				(clearance 0)
			)
			(min_thickness 0.25)
			(keepout
				(tracks allowed)
				(vias not_allowed)
				(pads allowed)
				(copperpour not_allowed)
				(footprints allowed)
			)
			(placement
				(enabled no)
				(sheetname "")
			)
			(fill
				(thermal_gap 0.5)
				(thermal_bridge_width 0.5)
				(island_removal_mode 0)
			)
			(polygon
				(pts
					(xy 500.126 -151.3078) (xy 500.634 -151.3078) (xy 500.634 -151.6888) (xy 500.126 -151.6888)
				)
			)
		)
	)
)
